(kicad_pcb
	(version 20260206)
	(generator "pcbnew")
	(generator_version "10.0")
	(general
		(thickness 1.6)
		(legacy_teardrops no)
	)
	(paper "A4")
	(title_block
		(title "04192023_DAF0TMB3IC0_F0TG_MB_C_brd_V02_OCP.brd")
		(comment 1 "Grand Teton / footprints 4137-4143 of 8354")
	)
	(layers
		(0 "F.Cu" signal "TOP")
		(4 "In1.Cu" signal "GND")
		(6 "In2.Cu" signal "IN1")
		(8 "In3.Cu" signal "GND1")
		(10 "In4.Cu" signal "IN2")
		(12 "In5.Cu" signal "GND2")
		(14 "In6.Cu" signal "IN3")
		(16 "In7.Cu" signal "GND3")
		(18 "In8.Cu" signal "VCC")
		(20 "In9.Cu" signal "VCC1")
		(22 "In10.Cu" signal "GND4")
		(24 "In11.Cu" signal "IN4")
		(26 "In12.Cu" signal "GND5")
		(28 "In13.Cu" signal "IN5")
		(30 "In14.Cu" signal "GND6")
		(32 "In15.Cu" signal "IN6")
		(34 "In16.Cu" signal "GND7")
		(2 "B.Cu" signal "BOTTOM")
		(9 "F.Adhes" user "F.Adhesive")
		(11 "B.Adhes" user "B.Adhesive")
		(13 "F.Paste" user "Package Geometry/Pastemask Top")
		(15 "B.Paste" user "Package Geometry/Pastemask Bottom")
		(5 "F.SilkS" user "Ref Des/Silkscreen Top")
		(7 "B.SilkS" user "Ref Des/Silkscreen Bottom")
		(1 "F.Mask" user "Board Geometry/Soldermask Top")
		(3 "B.Mask" user "Board Geometry/Soldermask Bottom")
		(17 "Dwgs.User" user "User.Drawings")
		(19 "Cmts.User" user "User.Comments")
		(21 "Eco1.User" user "User.Eco1")
		(23 "Eco2.User" user "User.Eco2")
		(25 "Edge.Cuts" user "Board Geometry/Outline")
		(27 "Margin" user)
		(31 "F.CrtYd" user "Package Geometry/Place Bound Top")
		(29 "B.CrtYd" user "Package Geometry/Place Bound Bottom")
		(35 "F.Fab" user "Ref Des/Assembly Top")
		(33 "B.Fab" user "Ref Des/Assembly Bottom")
	)
	(footprint ""
		(layer "F.Cu")
		(at 63.405258 -162.790886)
		(property "Reference" "PC127_6"
			(at 0 0 0)
			(layer "F.SilkS")
			(hide yes)
			(effects
				(font
					(size 1.27 1.27)
				)
			)
		)
		(property "Value" ""
			(at 0 0 0)
			(layer "F.Fab")
			(effects
				(font
					(size 1.27 1.27)
				)
			)
		)
		(duplicate_pad_numbers_are_jumpers no)
		(fp_line
			(start -0.7874 -0.4064)
			(end 0.7874 -0.4064)
			(stroke
				(width 0.1524)
				(type default)
			)
			(layer "F.SilkS")
		)
		(fp_line
			(start -0.7874 0.4064)
			(end -0.7874 -0.4064)
			(stroke
				(width 0.1524)
				(type default)
			)
			(layer "F.SilkS")
		)
		(fp_line
			(start 0.7874 -0.4064)
			(end 0.7874 0.4064)
			(stroke
				(width 0.1524)
				(type default)
			)
			(layer "F.SilkS")
		)
		(fp_line
			(start 0.7874 0.4064)
			(end -0.7874 0.4064)
			(stroke
				(width 0.1524)
				(type default)
			)
			(layer "F.SilkS")
		)
		(fp_line
			(start -0.67945 -0.305054)
			(end -0.12065 -0.305054)
			(stroke
				(width 0.1)
				(type default)
			)
			(layer "F.Fab")
		)
		(fp_line
			(start -0.67945 0.3048)
			(end -0.67945 -0.305054)
			(stroke
				(width 0.1)
				(type default)
			)
			(layer "F.Fab")
		)
		(fp_line
			(start -0.12065 -0.305054)
			(end -0.12065 -0.2794)
			(stroke
				(width 0.1)
				(type default)
			)
			(layer "F.Fab")
		)
		(fp_line
			(start -0.12065 -0.2794)
			(end 0.12065 -0.2794)
			(stroke
				(width 0.1)
				(type default)
			)
			(layer "F.Fab")
		)
		(fp_line
			(start -0.12065 0.2794)
			(end -0.12065 0.3048)
			(stroke
				(width 0.1)
				(type default)
			)
			(layer "F.Fab")
		)
		(fp_line
			(start -0.12065 0.3048)
			(end -0.67945 0.3048)
			(stroke
				(width 0.1)
				(type default)
			)
			(layer "F.Fab")
		)
		(fp_line
			(start 0.120396 0.2794)
			(end -0.12065 0.2794)
			(stroke
				(width 0.1)
				(type default)
			)
			(layer "F.Fab")
		)
		(fp_line
			(start 0.120396 0.3048)
			(end 0.120396 0.2794)
			(stroke
				(width 0.1)
				(type default)
			)
			(layer "F.Fab")
		)
		(fp_line
			(start 0.12065 -0.3048)
			(end 0.67945 -0.3048)
			(stroke
				(width 0.1)
				(type default)
			)
			(layer "F.Fab")
		)
		(fp_line
			(start 0.12065 -0.2794)
			(end 0.12065 -0.3048)
			(stroke
				(width 0.1)
				(type default)
			)
			(layer "F.Fab")
		)
		(fp_line
			(start 0.67945 -0.3048)
			(end 0.67945 0.3048)
			(stroke
				(width 0.1)
				(type default)
			)
			(layer "F.Fab")
		)
		(fp_line
			(start 0.67945 0.3048)
			(end 0.120396 0.3048)
			(stroke
				(width 0.1)
				(type default)
			)
			(layer "F.Fab")
		)
		(pad "1" smd circle
			(at -0.40005 0)
			(size 0 0)
			(layers "F.Cu" "F.Mask" "F.Paste")
			(net "SW_P12V_AUX_PVDDCR_CPU0_P1_FLT")
		)
		(pad "2" smd circle
			(at 0.40005 0)
			(size 0 0)
			(layers "F.Cu" "F.Mask" "F.Paste")
			(net "GND")
		)
	)
	(footprint ""
		(layer "F.Cu")
		(at 370.139468 -32.573468)
		(property "Reference" "C1354"
			(at 0 0 0)
			(layer "F.SilkS")
			(hide yes)
			(effects
				(font
					(size 1.27 1.27)
				)
			)
		)
		(property "Value" ""
			(at 0 0 0)
			(layer "F.Fab")
			(effects
				(font
					(size 1.27 1.27)
				)
			)
		)
		(duplicate_pad_numbers_are_jumpers no)
		(fp_line
			(start -0.7874 -0.4064)
			(end 0.7874 -0.4064)
			(stroke
				(width 0.1524)
				(type default)
			)
			(layer "F.SilkS")
		)
		(fp_line
			(start -0.7874 0.4064)
			(end -0.7874 -0.4064)
			(stroke
				(width 0.1524)
				(type default)
			)
			(layer "F.SilkS")
		)
		(fp_line
			(start 0.7874 -0.4064)
			(end 0.7874 0.4064)
			(stroke
				(width 0.1524)
				(type default)
			)
			(layer "F.SilkS")
		)
		(fp_line
			(start 0.7874 0.4064)
			(end -0.7874 0.4064)
			(stroke
				(width 0.1524)
				(type default)
			)
			(layer "F.SilkS")
		)
		(fp_line
			(start -0.67945 -0.305054)
			(end -0.12065 -0.305054)
			(stroke
				(width 0.1)
				(type default)
			)
			(layer "F.Fab")
		)
		(fp_line
			(start -0.67945 0.3048)
			(end -0.67945 -0.305054)
			(stroke
				(width 0.1)
				(type default)
			)
			(layer "F.Fab")
		)
		(fp_line
			(start -0.12065 -0.305054)
			(end -0.12065 -0.2794)
			(stroke
				(width 0.1)
				(type default)
			)
			(layer "F.Fab")
		)
		(fp_line
			(start -0.12065 -0.2794)
			(end 0.12065 -0.2794)
			(stroke
				(width 0.1)
				(type default)
			)
			(layer "F.Fab")
		)
		(fp_line
			(start -0.12065 0.2794)
			(end -0.12065 0.3048)
			(stroke
				(width 0.1)
				(type default)
			)
			(layer "F.Fab")
		)
		(fp_line
			(start -0.12065 0.3048)
			(end -0.67945 0.3048)
			(stroke
				(width 0.1)
				(type default)
			)
			(layer "F.Fab")
		)
		(fp_line
			(start 0.120396 0.2794)
			(end -0.12065 0.2794)
			(stroke
				(width 0.1)
				(type default)
			)
			(layer "F.Fab")
		)
		(fp_line
			(start 0.120396 0.3048)
			(end 0.120396 0.2794)
			(stroke
				(width 0.1)
				(type default)
			)
			(layer "F.Fab")
		)
		(fp_line
			(start 0.12065 -0.3048)
			(end 0.67945 -0.3048)
			(stroke
				(width 0.1)
				(type default)
			)
			(layer "F.Fab")
		)
		(fp_line
			(start 0.12065 -0.2794)
			(end 0.12065 -0.3048)
			(stroke
				(width 0.1)
				(type default)
			)
			(layer "F.Fab")
		)
		(fp_line
			(start 0.67945 -0.3048)
			(end 0.67945 0.3048)
			(stroke
				(width 0.1)
				(type default)
			)
			(layer "F.Fab")
		)
		(fp_line
			(start 0.67945 0.3048)
			(end 0.120396 0.3048)
			(stroke
				(width 0.1)
				(type default)
			)
			(layer "F.Fab")
		)
		(pad "1" smd circle
			(at -0.40005 0)
			(size 0 0)
			(layers "F.Cu" "F.Mask" "F.Paste")
			(net "P3V3_AUX")
		)
		(pad "2" smd circle
			(at 0.40005 0)
			(size 0 0)
			(layers "F.Cu" "F.Mask" "F.Paste")
			(net "GND")
		)
	)
	(footprint ""
		(layer "F.Cu")
		(at 409.853638 -163.684966 90)
		(property "Reference" "PC609_3"
			(at 0 0 90)
			(layer "F.SilkS")
			(hide yes)
			(effects
				(font
					(size 1.27 1.27)
				)
			)
		)
		(property "Value" ""
			(at 0 0 90)
			(layer "F.Fab")
			(effects
				(font
					(size 1.27 1.27)
				)
			)
		)
		(duplicate_pad_numbers_are_jumpers no)
		(fp_line
			(start 0.7874 -0.4064)
			(end 0.7874 0.4064)
			(stroke
				(width 0.1524)
				(type default)
			)
			(layer "F.SilkS")
		)
		(fp_line
			(start -0.7874 -0.4064)
			(end 0.7874 -0.4064)
			(stroke
				(width 0.1524)
				(type default)
			)
			(layer "F.SilkS")
		)
		(fp_line
			(start 0.7874 0.4064)
			(end -0.7874 0.4064)
			(stroke
				(width 0.1524)
				(type default)
			)
			(layer "F.SilkS")
		)
		(fp_line
			(start -0.7874 0.4064)
			(end -0.7874 -0.4064)
			(stroke
				(width 0.1524)
				(type default)
			)
			(layer "F.SilkS")
		)
		(fp_line
			(start -0.12065 -0.305054)
			(end -0.12065 -0.2794)
			(stroke
				(width 0.1)
				(type default)
			)
			(layer "F.Fab")
		)
		(fp_line
			(start -0.67945 -0.305054)
			(end -0.12065 -0.305054)
			(stroke
				(width 0.1)
				(type default)
			)
			(layer "F.Fab")
		)
		(fp_line
			(start 0.67945 -0.3048)
			(end 0.67945 0.3048)
			(stroke
				(width 0.1)
				(type default)
			)
			(layer "F.Fab")
		)
		(fp_line
			(start 0.12065 -0.3048)
			(end 0.67945 -0.3048)
			(stroke
				(width 0.1)
				(type default)
			)
			(layer "F.Fab")
		)
		(fp_line
			(start 0.12065 -0.2794)
			(end 0.12065 -0.3048)
			(stroke
				(width 0.1)
				(type default)
			)
			(layer "F.Fab")
		)
		(fp_line
			(start -0.12065 -0.2794)
			(end 0.12065 -0.2794)
			(stroke
				(width 0.1)
				(type default)
			)
			(layer "F.Fab")
		)
		(fp_line
			(start 0.120396 0.2794)
			(end -0.12065 0.2794)
			(stroke
				(width 0.1)
				(type default)
			)
			(layer "F.Fab")
		)
		(fp_line
			(start -0.12065 0.2794)
			(end -0.12065 0.3048)
			(stroke
				(width 0.1)
				(type default)
			)
			(layer "F.Fab")
		)
		(fp_line
			(start 0.67945 0.3048)
			(end 0.120396 0.3048)
			(stroke
				(width 0.1)
				(type default)
			)
			(layer "F.Fab")
		)
		(fp_line
			(start 0.120396 0.3048)
			(end 0.120396 0.2794)
			(stroke
				(width 0.1)
				(type default)
			)
			(layer "F.Fab")
		)
		(fp_line
			(start -0.12065 0.3048)
			(end -0.67945 0.3048)
			(stroke
				(width 0.1)
				(type default)
			)
			(layer "F.Fab")
		)
		(fp_line
			(start -0.67945 0.3048)
			(end -0.67945 -0.305054)
			(stroke
				(width 0.1)
				(type default)
			)
			(layer "F.Fab")
		)
		(pad "1" smd circle
			(at -0.40005 0 90)
			(size 0 0)
			(layers "F.Cu" "F.Mask" "F.Paste")
			(net "SW_P12V_AUX_PVDDCR_SOC_P0_FLT")
		)
		(pad "2" smd circle
			(at 0.40005 0 90)
			(size 0 0)
			(layers "F.Cu" "F.Mask" "F.Paste")
			(net "GND")
		)
	)
	(footprint ""
		(layer "F.Cu")
		(at 124.972826 -408.517344 -90)
		(property "Reference" "C6699"
			(at 0 0 270)
			(layer "F.SilkS")
			(hide yes)
			(effects
				(font
					(size 1.27 1.27)
				)
			)
		)
		(property "Value" ""
			(at 0 0 270)
			(layer "F.Fab")
			(effects
				(font
					(size 1.27 1.27)
				)
			)
		)
		(duplicate_pad_numbers_are_jumpers no)
		(fp_line
			(start -0.299974 0.150114)
			(end -0.299974 -0.150114)
			(stroke
				(width 0.1)
				(type default)
			)
			(layer "F.Fab")
		)
		(fp_line
			(start 0.299974 0.150114)
			(end -0.299974 0.150114)
			(stroke
				(width 0.1)
				(type default)
			)
			(layer "F.Fab")
		)
		(fp_line
			(start -0.299974 -0.150114)
			(end 0.299974 -0.150114)
			(stroke
				(width 0.1)
				(type default)
			)
			(layer "F.Fab")
		)
		(fp_line
			(start 0.299974 -0.150114)
			(end 0.299974 0.150114)
			(stroke
				(width 0.1)
				(type default)
			)
			(layer "F.Fab")
		)
		(pad "1" smd rect
			(at -0.2667 0 270)
			(size 0.3048 0.381)
			(layers "F.Cu" "F.Mask" "F.Paste")
			(net "P5E_CPU1_P2_TX_BUF_C_DP<3>")
		)
		(pad "2" smd rect
			(at 0.2667 0 270)
			(size 0.3048 0.381)
			(layers "F.Cu" "F.Mask" "F.Paste")
			(net "P5E_CPU1_P2_TX_BUF_DP<3>")
		)
	)
	(footprint ""
		(layer "F.Cu")
		(at 118.491 -420.497 180)
		(property "Reference" "C1975"
			(at 0 0 180)
			(layer "F.SilkS")
			(hide yes)
			(effects
				(font
					(size 1.27 1.27)
				)
			)
		)
		(property "Value" ""
			(at 0 0 180)
			(layer "F.Fab")
			(effects
				(font
					(size 1.27 1.27)
				)
			)
		)
		(duplicate_pad_numbers_are_jumpers no)
		(fp_line
			(start 0.7874 0.4064)
			(end -0.7874 0.4064)
			(stroke
				(width 0.1524)
				(type default)
			)
			(layer "F.SilkS")
		)
		(fp_line
			(start 0.7874 -0.4064)
			(end 0.7874 0.4064)
			(stroke
				(width 0.1524)
				(type default)
			)
			(layer "F.SilkS")
		)
		(fp_line
			(start -0.7874 0.4064)
			(end -0.7874 -0.4064)
			(stroke
				(width 0.1524)
				(type default)
			)
			(layer "F.SilkS")
		)
		(fp_line
			(start -0.7874 -0.4064)
			(end 0.7874 -0.4064)
			(stroke
				(width 0.1524)
				(type default)
			)
			(layer "F.SilkS")
		)
		(fp_line
			(start 0.67945 0.3048)
			(end 0.120396 0.3048)
			(stroke
				(width 0.1)
				(type default)
			)
			(layer "F.Fab")
		)
		(fp_line
			(start 0.67945 -0.3048)
			(end 0.67945 0.3048)
			(stroke
				(width 0.1)
				(type default)
			)
			(layer "F.Fab")
		)
		(fp_line
			(start 0.12065 -0.2794)
			(end 0.12065 -0.3048)
			(stroke
				(width 0.1)
				(type default)
			)
			(layer "F.Fab")
		)
		(fp_line
			(start 0.12065 -0.3048)
			(end 0.67945 -0.3048)
			(stroke
				(width 0.1)
				(type default)
			)
			(layer "F.Fab")
		)
		(fp_line
			(start 0.120396 0.3048)
			(end 0.120396 0.2794)
			(stroke
				(width 0.1)
				(type default)
			)
			(layer "F.Fab")
		)
		(fp_line
			(start 0.120396 0.2794)
			(end -0.12065 0.2794)
			(stroke
				(width 0.1)
				(type default)
			)
			(layer "F.Fab")
		)
		(fp_line
			(start -0.12065 0.3048)
			(end -0.67945 0.3048)
			(stroke
				(width 0.1)
				(type default)
			)
			(layer "F.Fab")
		)
		(fp_line
			(start -0.12065 0.2794)
			(end -0.12065 0.3048)
			(stroke
				(width 0.1)
				(type default)
			)
			(layer "F.Fab")
		)
		(fp_line
			(start -0.12065 -0.2794)
			(end 0.12065 -0.2794)
			(stroke
				(width 0.1)
				(type default)
			)
			(layer "F.Fab")
		)
		(fp_line
			(start -0.12065 -0.305054)
			(end -0.12065 -0.2794)
			(stroke
				(width 0.1)
				(type default)
			)
			(layer "F.Fab")
		)
		(fp_line
			(start -0.67945 0.3048)
			(end -0.67945 -0.305054)
			(stroke
				(width 0.1)
				(type default)
			)
			(layer "F.Fab")
		)
		(fp_line
			(start -0.67945 -0.305054)
			(end -0.12065 -0.305054)
			(stroke
				(width 0.1)
				(type default)
			)
			(layer "F.Fab")
		)
		(pad "1" smd circle
			(at -0.40005 0 180)
			(size 0 0)
			(layers "F.Cu" "F.Mask" "F.Paste")
			(net "GPU_HMC_PRSNT_ISO_N")
		)
		(pad "2" smd circle
			(at 0.40005 0 180)
			(size 0 0)
			(layers "F.Cu" "F.Mask" "F.Paste")
			(net "GND")
		)
	)
	(footprint ""
		(layer "F.Cu")
		(at 330.269342 -392.1252)
		(property "Reference" "R1034"
			(at 0 0 0)
			(layer "F.SilkS")
			(hide yes)
			(effects
				(font
					(size 1.27 1.27)
				)
			)
		)
		(property "Value" ""
			(at 0 0 0)
			(layer "F.Fab")
			(effects
				(font
					(size 1.27 1.27)
				)
			)
		)
		(duplicate_pad_numbers_are_jumpers no)
		(fp_line
			(start -0.32512 -0.175006)
			(end 0.32512 -0.175006)
			(stroke
				(width 0.1)
				(type default)
			)
			(layer "F.Fab")
		)
		(fp_line
			(start -0.32512 0.175006)
			(end -0.32512 -0.175006)
			(stroke
				(width 0.1)
				(type default)
			)
			(layer "F.Fab")
		)
		(fp_line
			(start 0.32512 -0.175006)
			(end 0.32512 0.175006)
			(stroke
				(width 0.1)
				(type default)
			)
			(layer "F.Fab")
		)
		(fp_line
			(start 0.32512 0.175006)
			(end -0.32512 0.175006)
			(stroke
				(width 0.1)
				(type default)
			)
			(layer "F.Fab")
		)
		(pad "1" smd rect
			(at -0.2667 0)
			(size 0.3048 0.381)
			(layers "F.Cu" "F.Mask" "F.Paste")
			(net "P1V8_CPU0_RT_1D")
		)
		(pad "2" smd rect
			(at 0.2667 0 180)
			(size 0.3048 0.381)
			(layers "F.Cu" "F.Mask" "F.Paste")
			(net "TEST2_RT_CPU0_P1")
		)
	)
	(footprint ""
		(layer "F.Cu")
		(at 110.235238 -41.17975 -90)
		(property "Reference" "R6292"
			(at 0 0 270)
			(layer "F.SilkS")
			(hide yes)
			(effects
				(font
					(size 1.27 1.27)
				)
			)
		)
		(property "Value" ""
			(at 0 0 270)
			(layer "F.Fab")
			(effects
				(font
					(size 1.27 1.27)
				)
			)
		)
		(duplicate_pad_numbers_are_jumpers no)
		(fp_line
			(start -0.7874 0.4064)
			(end -0.7874 -0.4064)
			(stroke
				(width 0.1524)
				(type default)
			)
			(layer "F.SilkS")
		)
		(fp_line
			(start 0.7874 0.4064)
			(end -0.7874 0.4064)
			(stroke
				(width 0.1524)
				(type default)
			)
			(layer "F.SilkS")
		)
		(fp_line
			(start -0.7874 -0.4064)
			(end 0.7874 -0.4064)
			(stroke
				(width 0.1524)
				(type default)
			)
			(layer "F.SilkS")
		)
		(fp_line
			(start 0.7874 -0.4064)
			(end 0.7874 0.4064)
			(stroke
				(width 0.1524)
				(type default)
			)
			(layer "F.SilkS")
		)
		(fp_line
			(start -0.67945 0.3048)
			(end -0.67945 -0.305054)
			(stroke
				(width 0.1)
				(type default)
			)
			(layer "F.Fab")
		)
		(fp_line
			(start -0.12065 0.3048)
			(end -0.67945 0.3048)
			(stroke
				(width 0.1)
				(type default)
			)
			(layer "F.Fab")
		)
		(fp_line
			(start 0.120396 0.3048)
			(end 0.120396 0.2794)
			(stroke
				(width 0.1)
				(type default)
			)
			(layer "F.Fab")
		)
		(fp_line
			(start 0.67945 0.3048)
			(end 0.120396 0.3048)
			(stroke
				(width 0.1)
				(type default)
			)
			(layer "F.Fab")
		)
		(fp_line
			(start -0.12065 0.2794)
			(end -0.12065 0.3048)
			(stroke
				(width 0.1)
				(type default)
			)
			(layer "F.Fab")
		)
		(fp_line
			(start 0.120396 0.2794)
			(end -0.12065 0.2794)
			(stroke
				(width 0.1)
				(type default)
			)
			(layer "F.Fab")
		)
		(fp_line
			(start -0.12065 -0.2794)
			(end 0.12065 -0.2794)
			(stroke
				(width 0.1)
				(type default)
			)
			(layer "F.Fab")
		)
		(fp_line
			(start 0.12065 -0.2794)
			(end 0.12065 -0.3048)
			(stroke
				(width 0.1)
				(type default)
			)
			(layer "F.Fab")
		)
		(fp_line
			(start 0.12065 -0.3048)
			(end 0.67945 -0.3048)
			(stroke
				(width 0.1)
				(type default)
			)
			(layer "F.Fab")
		)
		(fp_line
			(start 0.67945 -0.3048)
			(end 0.67945 0.3048)
			(stroke
				(width 0.1)
				(type default)
			)
			(layer "F.Fab")
		)
		(fp_line
			(start -0.67945 -0.305054)
			(end -0.12065 -0.305054)
			(stroke
				(width 0.1)
				(type default)
			)
			(layer "F.Fab")
		)
		(fp_line
			(start -0.12065 -0.305054)
			(end -0.12065 -0.2794)
			(stroke
				(width 0.1)
				(type default)
			)
			(layer "F.Fab")
		)
		(pad "1" smd circle
			(at -0.40005 0 270)
			(size 0 0)
			(layers "F.Cu" "F.Mask" "F.Paste")
			(net "P3V3_AUX")
		)
		(pad "2" smd circle
			(at 0.40005 0 270)
			(size 0 0)
			(layers "F.Cu" "F.Mask" "F.Paste")
			(net "USB_HUB2_TI_GANGED")
		)
	)
)
